# BASEBOARD_FAB2 (Tioga Pass) — schematic netlist excerpt (pin names and nets, part order shuffled) for the footprints in the layout excerpt that follows; sources: Cadence DE-HDL packaged netlist, KiCad conversion of Wiwynn_Tioga_Pass_MB.brd

R4T9  RES  20.0 1% CHIP  pkg 0402  page 99 : A = SMB_DDR_ABC_VPP_SCL_R ; B = SMB_DDR_ABC_VPP_SCL
C8P30  CAP  100UF 4V 20% X5R  pkg 0805  page 225 : A = PVDDQ_GHJ ; B = GND
C2M3  CAP_A  0.1UF 16V 10% X7R  pkg 0402V  page 116 : A = P2E_SSB_BMC_TX_DN ; B = P2E_SSB_BMC_TX_C_DN

(kicad_pcb
	(version 20260206)
	(generator "pcbnew")
	(generator_version "10.0")
	(general
		(thickness 1.6)
		(legacy_teardrops no)
	)
	(paper "A4")
	(title_block
		(title "Wiwynn_Tioga_Pass_MB.brd")
		(comment 1 "Tioga Pass / footprints 4613-4615 of 4770")
	)
	(layers
		(0 "F.Cu" signal "TOP")
		(4 "In1.Cu" signal "L2GND")
		(6 "In2.Cu" signal "L3")
		(8 "In3.Cu" signal "L4GND")
		(10 "In4.Cu" signal "L5")
		(12 "In5.Cu" signal "L6GND")
		(14 "In6.Cu" signal "L7VCC")
		(16 "In7.Cu" signal "L8VCC")
		(18 "In8.Cu" signal "L9GND")
		(20 "In9.Cu" signal "L10")
		(22 "In10.Cu" signal "L11GND")
		(24 "In11.Cu" signal "L12")
		(26 "In12.Cu" signal "L13GND")
		(2 "B.Cu" signal "BOTTOM")
		(9 "F.Adhes" user "F.Adhesive")
		(11 "B.Adhes" user "B.Adhesive")
		(13 "F.Paste" user "Package Geometry/Pastemask Top")
		(15 "B.Paste" user "Package Geometry/Pastemask Bottom")
		(5 "F.SilkS" user "Ref Des/Silkscreen Top")
		(7 "B.SilkS" user "Ref Des/Silkscreen Bottom")
		(1 "F.Mask" user "Board Geometry/Soldermask Top")
		(3 "B.Mask" user "Board Geometry/Soldermask Bottom")
		(17 "Dwgs.User" user "User.Drawings")
		(19 "Cmts.User" user "User.Comments")
		(21 "Eco1.User" user "User.Eco1")
		(23 "Eco2.User" user "User.Eco2")
		(25 "Edge.Cuts" user "Board Geometry/Outline")
		(27 "Margin" user)
		(31 "F.CrtYd" user "Package Geometry/Place Bound Top")
		(29 "B.CrtYd" user "Package Geometry/Place Bound Bottom")
		(35 "F.Fab" user "Ref Des/Assembly Top")
		(33 "B.Fab" user "Ref Des/Assembly Bottom")
	)
	(footprint ""
		(layer "B.Cu")
		(at 399.530824 -125.627384 90)
		(property "Reference" "C2M3"
			(at 0 0 90)
			(layer "B.SilkS")
			(hide yes)
			(effects
				(font
					(size 1.27 1.27)
				)
				(justify mirror)
			)
		)
		(property "Value" ""
			(at 0 0 90)
			(layer "B.Fab")
			(effects
				(font
					(size 1.27 1.27)
				)
				(justify mirror)
			)
		)
		(duplicate_pad_numbers_are_jumpers no)
		(fp_poly
			(pts
				(xy -0.3048 -0.1016) (xy -0.3048 0.9906) (xy 0.3048 0.9906) (xy 0.3048 -0.1016)
			)
			(stroke
				(width 0)
				(type default)
			)
			(fill no)
			(layer "B.CrtYd")
		)
		(fp_line
			(start 0.3048 -0.1016)
			(end 0.3048 0.9906)
			(stroke
				(width 0.1)
				(type default)
			)
			(layer "B.Fab")
		)
		(fp_line
			(start -0.3048 -0.1016)
			(end 0.3048 -0.1016)
			(stroke
				(width 0.1)
				(type default)
			)
			(layer "B.Fab")
		)
		(fp_line
			(start 0.3048 0.9906)
			(end -0.3048 0.9906)
			(stroke
				(width 0.1)
				(type default)
			)
			(layer "B.Fab")
		)
		(fp_line
			(start -0.3048 0.9906)
			(end -0.3048 -0.1016)
			(stroke
				(width 0.1)
				(type default)
			)
			(layer "B.Fab")
		)
		(pad "1" smd rect
			(at 0 0 270)
			(size 0.508 0.508)
			(layers "B.Cu" "B.Mask" "B.Paste")
			(net "P2E_SSB_BMC_TX_DN")
		)
		(pad "2" smd rect
			(at 0 0.889 270)
			(size 0.508 0.508)
			(layers "B.Cu" "B.Mask" "B.Paste")
			(net "P2E_SSB_BMC_TX_C_DN")
		)
		(zone
			(layer "B.Cu")
			(hatch none 0.5)
			(connect_pads
				(clearance 0)
			)
			(min_thickness 0.25)
			(keepout
				(tracks allowed)
				(vias not_allowed)
				(pads allowed)
				(copperpour not_allowed)
				(footprints allowed)
			)
			(placement
				(enabled no)
				(sheetname "")
			)
			(fill
				(thermal_gap 0.5)
				(thermal_bridge_width 0.5)
				(island_removal_mode 0)
			)
			(polygon
				(pts
					(xy 399.784824 -125.881384) (xy 399.784824 -125.373384) (xy 400.165824 -125.373384) (xy 400.165824 -125.881384)
				)
			)
		)
		(zone
			(layer "B.Cu")
			(hatch none 0.5)
			(connect_pads
				(clearance 0)
			)
			(min_thickness 0.25)
			(keepout
				(tracks not_allowed)
				(vias allowed)
				(pads allowed)
				(copperpour not_allowed)
				(footprints allowed)
			)
			(placement
				(enabled no)
				(sheetname "")
			)
			(fill
				(thermal_gap 0.5)
				(thermal_bridge_width 0.5)
				(island_removal_mode 0)
			)
			(polygon
				(pts
					(xy 400.165824 -125.881384) (xy 400.165824 -125.373384) (xy 399.784824 -125.373384) (xy 399.784824 -125.881384)
				)
			)
		)
	)
	(footprint ""
		(layer "B.Cu")
		(at 322.9737 -27.411172 90)
		(property "Reference" "R4T9"
			(at 0 0 90)
			(layer "B.SilkS")
			(hide yes)
			(effects
				(font
					(size 1.27 1.27)
				)
				(justify mirror)
			)
		)
		(property "Value" ""
			(at 0 0 90)
			(layer "B.Fab")
			(effects
				(font
					(size 1.27 1.27)
				)
				(justify mirror)
			)
		)
		(duplicate_pad_numbers_are_jumpers no)
		(fp_poly
			(pts
				(xy 0.2794 -0.1016) (xy -0.2794 -0.1016) (xy -0.2794 0.9906) (xy 0.2794 0.9906)
			)
			(stroke
				(width 0)
				(type default)
			)
			(fill no)
			(layer "B.CrtYd")
		)
		(fp_line
			(start 0.2794 -0.1016)
			(end 0.2794 0.9906)
			(stroke
				(width 0.1)
				(type default)
			)
			(layer "B.Fab")
		)
		(fp_line
			(start -0.2794 -0.1016)
			(end 0.2794 -0.1016)
			(stroke
				(width 0.1)
				(type default)
			)
			(layer "B.Fab")
		)
		(fp_line
			(start 0.2794 0.9906)
			(end -0.2794 0.9906)
			(stroke
				(width 0.1)
				(type default)
			)
			(layer "B.Fab")
		)
		(fp_line
			(start -0.2794 0.9906)
			(end -0.2794 -0.1016)
			(stroke
				(width 0.1)
				(type default)
			)
			(layer "B.Fab")
		)
		(pad "1" smd rect
			(at 0 0 270)
			(size 0.508 0.508)
			(layers "B.Cu" "B.Mask" "B.Paste")
			(net "SMB_DDR_ABC_VPP_SCL_R")
		)
		(pad "2" smd rect
			(at 0 0.889 270)
			(size 0.508 0.508)
			(layers "B.Cu" "B.Mask" "B.Paste")
			(net "SMB_DDR_ABC_VPP_SCL")
		)
		(zone
			(layer "B.Cu")
			(hatch none 0.5)
			(connect_pads
				(clearance 0)
			)
			(min_thickness 0.25)
			(keepout
				(tracks allowed)
				(vias not_allowed)
				(pads allowed)
				(copperpour not_allowed)
				(footprints allowed)
			)
			(placement
				(enabled no)
				(sheetname "")
			)
			(fill
				(thermal_gap 0.5)
				(thermal_bridge_width 0.5)
				(island_removal_mode 0)
			)
			(polygon
				(pts
					(xy 323.2277 -27.665172) (xy 323.2277 -27.157172) (xy 323.6087 -27.157172) (xy 323.6087 -27.665172)
				)
			)
		)
		(zone
			(layer "B.Cu")
			(hatch none 0.5)
			(connect_pads
				(clearance 0)
			)
			(min_thickness 0.25)
			(keepout
				(tracks not_allowed)
				(vias allowed)
				(pads allowed)
				(copperpour not_allowed)
				(footprints allowed)
			)
			(placement
				(enabled no)
				(sheetname "")
			)
			(fill
				(thermal_gap 0.5)
				(thermal_bridge_width 0.5)
				(island_removal_mode 0)
			)
			(polygon
				(pts
					(xy 323.6087 -27.665172) (xy 323.6087 -27.157172) (xy 323.2277 -27.157172) (xy 323.2277 -27.665172)
				)
			)
		)
	)
	(footprint ""
		(layer "B.Cu")
		(at 99.427792 -69.098414 -90)
		(property "Reference" "C8P30"
			(at 0 0 90)
			(layer "B.SilkS")
			(hide yes)
			(effects
				(font
					(size 1.27 1.27)
				)
				(justify mirror)
			)
		)
		(property "Value" ""
			(at 0 0 90)
			(layer "B.Fab")
			(effects
				(font
					(size 1.27 1.27)
				)
				(justify mirror)
			)
		)
		(duplicate_pad_numbers_are_jumpers no)
		(fp_poly
			(pts
				(xy 0.7239 -0.2159) (xy -0.7239 -0.2159) (xy -0.7239 1.9939) (xy 0.7239 1.9939)
			)
			(stroke
				(width 0)
				(type default)
			)
			(fill no)
			(layer "B.CrtYd")
		)
		(fp_line
			(start -0.7239 1.9939)
			(end -0.7239 -0.2159)
			(stroke
				(width 0.1)
				(type default)
			)
			(layer "B.Fab")
		)
		(fp_line
			(start 0.7239 1.9939)
			(end -0.7239 1.9939)
			(stroke
				(width 0.1)
				(type default)
			)
			(layer "B.Fab")
		)
		(fp_line
			(start -0.7239 -0.2159)
			(end 0.7239 -0.2159)
			(stroke
				(width 0.1)
				(type default)
			)
			(layer "B.Fab")
		)
		(fp_line
			(start 0.7239 -0.2159)
			(end 0.7239 1.9939)
			(stroke
				(width 0.1)
				(type default)
			)
			(layer "B.Fab")
		)
		(pad "1" smd rect
			(at 0 0 90)
			(size 1.27 1.016)
			(layers "B.Cu" "B.Mask" "B.Paste")
			(net "PVDDQ_GHJ")
		)
		(pad "2" smd rect
			(at 0 1.778 90)
			(size 1.27 1.016)
			(layers "B.Cu" "B.Mask" "B.Paste")
			(net "GND")
		)
		(zone
			(layer "B.Cu")
			(hatch none 0.5)
			(connect_pads
				(clearance 0)
			)
			(min_thickness 0.25)
			(keepout
				(tracks not_allowed)
				(vias allowed)
				(pads allowed)
				(copperpour not_allowed)
				(footprints allowed)
			)
			(placement
				(enabled no)
				(sheetname "")
			)
			(fill
				(thermal_gap 0.5)
				(thermal_bridge_width 0.5)
				(island_removal_mode 0)
			)
			(polygon
				(pts
					(xy 98.919792 -68.463414) (xy 98.919792 -69.733414) (xy 98.157792 -69.733414) (xy 98.157792 -68.463414)
				)
			)
		)
	)
)
